(kicad_pcb
	(version 20241229)
	(generator "pcbnew")
	(generator_version "9.0")
	(general
		(thickness 1.61)
		(legacy_teardrops no)
	)
	(paper "A3")
	(title_block
		(title "RDIMM DDR5 Tester")
		(date "2026-05-21")
		(rev "2.2.0")
		(company "Antmicro")
		(comment 9 "footprints 214-218 of 796")
	)
	(layers
		(0 "F.Cu" signal)
		(4 "In1.Cu" power)
		(6 "In2.Cu" mixed)
		(8 "In3.Cu" power)
		(10 "In4.Cu" mixed)
		(12 "In5.Cu" power)
		(14 "In6.Cu" mixed)
		(16 "In7.Cu" power)
		(18 "In8.Cu" power)
		(20 "In9.Cu" mixed)
		(22 "In10.Cu" power)
		(2 "B.Cu" signal)
		(9 "F.Adhes" user "F.Adhesive")
		(11 "B.Adhes" user "B.Adhesive")
		(13 "F.Paste" user)
		(15 "B.Paste" user)
		(5 "F.SilkS" user "F.Silkscreen")
		(7 "B.SilkS" user "B.Silkscreen")
		(1 "F.Mask" user)
		(3 "B.Mask" user)
		(17 "Dwgs.User" user "User.Drawings")
		(19 "Cmts.User" user "User.Comments")
		(21 "Eco1.User" user "User.Eco1")
		(23 "Eco2.User" user "User.Eco2")
		(25 "Edge.Cuts" user)
		(27 "Margin" user)
		(31 "F.CrtYd" user "F.Courtyard")
		(29 "B.CrtYd" user "B.Courtyard")
		(35 "F.Fab" user)
		(33 "B.Fab" user)
	)
	(footprint "antmicro-footprints:C_0402_1005Metric"
		(layer "F.Cu")
		(at 233.465001 180.725 90)
		(descr "Capacitor SMD 0402")
		(tags "capacitor SMD 0402")
		(property "Reference" "C210"
			(at -3.175 1.804999 90)
			(layer "F.SilkS")
			(effects
				(font
					(size 0.7 0.7)
					(thickness 0.15)
				)
				(justify left bottom)
			)
		)
		(property "Value" "C_4u7_25V_0402"
			(at -1.022927 2.155213 90)
			(layer "F.Fab")
			(effects
				(font
					(size 0.7 0.7)
					(thickness 0.15)
				)
				(justify left bottom)
			)
		)
		(property "Datasheet" "https://www.murata.com/products/productdetail?partno=GRM155C61E475ME15%23"
			(at 0 0 90)
			(layer "F.Fab")
			(hide yes)
			(effects
				(font
					(size 1.27 1.27)
					(thickness 0.15)
				)
			)
		)
		(property "MPN" "GRM155C61E475ME15J"
			(at 0 0 90)
			(unlocked yes)
			(layer "F.Fab")
			(hide yes)
			(effects
				(font
					(size 1 1)
					(thickness 0.15)
				)
			)
		)
		(property "Manufacturer" "Murata"
			(at 0 0 90)
			(unlocked yes)
			(layer "F.Fab")
			(hide yes)
			(effects
				(font
					(size 1 1)
					(thickness 0.15)
				)
			)
		)
		(property "License" "Apache-2.0"
			(at 0 0 90)
			(unlocked yes)
			(layer "F.Fab")
			(hide yes)
			(effects
				(font
					(size 1 1)
					(thickness 0.15)
				)
			)
		)
		(property "Author" "Antmicro"
			(at 0 0 90)
			(unlocked yes)
			(layer "F.Fab")
			(hide yes)
			(effects
				(font
					(size 1 1)
					(thickness 0.15)
				)
			)
		)
		(property "Val" "4u7"
			(at 0 0 90)
			(unlocked yes)
			(layer "F.Fab")
			(hide yes)
			(effects
				(font
					(size 1 1)
					(thickness 0.15)
				)
			)
		)
		(property "Voltage" "25V"
			(at 0 0 90)
			(unlocked yes)
			(layer "F.Fab")
			(hide yes)
			(effects
				(font
					(size 1 1)
					(thickness 0.15)
				)
			)
		)
		(property "Dielectric" "X5S"
			(at 0 0 90)
			(unlocked yes)
			(layer "F.Fab")
			(hide yes)
			(effects
				(font
					(size 1 1)
					(thickness 0.15)
				)
			)
		)
		(sheetname "/Supply/DC-DC VCCINT/")
		(sheetfile "dc-dc-vccint.kicad_sch")
		(attr smd)
		(fp_rect
			(start -0.925 -0.47)
			(end 0.925 0.47)
			(stroke
				(width 0.05)
				(type default)
			)
			(fill no)
			(layer "F.CrtYd")
		)
		(fp_line
			(start 0.504 -0.25)
			(end 0.504 0.248)
			(stroke
				(width 0.15)
				(type solid)
			)
			(layer "F.Fab")
		)
		(fp_line
			(start -0.494 -0.25)
			(end 0.504 -0.25)
			(stroke
				(width 0.15)
				(type solid)
			)
			(layer "F.Fab")
		)
		(fp_line
			(start 0.504 0.248)
			(end -0.494 0.248)
			(stroke
				(width 0.15)
				(type solid)
			)
			(layer "F.Fab")
		)
		(fp_line
			(start -0.494 0.248)
			(end -0.494 -0.25)
			(stroke
				(width 0.15)
				(type solid)
			)
			(layer "F.Fab")
		)
		(fp_text user "${REFERENCE}"
			(at -0.939 4.599 90)
			(layer "F.Fab")
			(effects
				(font
					(size 0.7 0.7)
					(thickness 0.15)
				)
				(justify left bottom)
			)
		)
		(fp_text user "Author: Antmicro"
			(at -0.939 3.399 90)
			(layer "F.Fab")
			(effects
				(font
					(size 0.7 0.7)
					(thickness 0.15)
				)
				(justify left bottom)
			)
		)
		(fp_text user "License: Apache-2.0"
			(at -0.939 5.799 90)
			(layer "F.Fab")
			(effects
				(font
					(size 0.7 0.7)
					(thickness 0.15)
				)
				(justify left bottom)
			)
		)
		(pad "1" smd roundrect
			(at -0.48 0 90)
			(size 0.59 0.64)
			(layers "F.Cu" "F.Mask" "F.Paste")
			(roundrect_rratio 0.25)
			(net 1 "GND")
			(pintype "passive")
		)
		(pad "2" smd roundrect
			(at 0.48 0 90)
			(size 0.59 0.64)
			(layers "F.Cu" "F.Mask" "F.Paste")
			(roundrect_rratio 0.25)
			(net 163 "/Supply/DC-DC VCCINT/V_{CC}")
			(pintype "passive")
		)
	)
	(footprint "antmicro-footprints:Vishay_PowerPAK_1212-8_Single"
		(layer "F.Cu")
		(at 247.1255 121.25 -90)
		(descr "PowerPAK 1212-8 Single")
		(tags "Vishay PowerPAK 1212-8 Single")
		(property "Reference" "Q29"
			(at 3.05 -1.9745 180)
			(layer "F.SilkS")
			(effects
				(font
					(size 0.7 0.7)
					(thickness 0.15)
				)
				(justify right bottom)
			)
		)
		(property "Value" "SI7613DN-T1-GE3"
			(at 0 2.7 90)
			(layer "F.Fab")
			(effects
				(font
					(size 0.7 0.7)
					(thickness 0.15)
				)
				(justify right bottom)
			)
		)
		(property "Datasheet" "https://www.vishay.com/docs/64809/si7613dn.pdf"
			(at 0 0 90)
			(layer "F.Fab")
			(hide yes)
			(effects
				(font
					(size 1.27 1.27)
					(thickness 0.15)
				)
			)
		)
		(property "MPN" "SI7613DN-T1-GE3"
			(at 0 0 270)
			(unlocked yes)
			(layer "F.Fab")
			(hide yes)
			(effects
				(font
					(size 1 1)
					(thickness 0.15)
				)
			)
		)
		(property "Manufacturer" "Vishay"
			(at 0 0 270)
			(unlocked yes)
			(layer "F.Fab")
			(hide yes)
			(effects
				(font
					(size 1 1)
					(thickness 0.15)
				)
			)
		)
		(property "Author" "Antmicro"
			(at 0 0 270)
			(unlocked yes)
			(layer "F.Fab")
			(hide yes)
			(effects
				(font
					(size 1 1)
					(thickness 0.15)
				)
			)
		)
		(property "License" "Apache-2.0"
			(at 0 0 270)
			(unlocked yes)
			(layer "F.Fab")
			(hide yes)
			(effects
				(font
					(size 1 1)
					(thickness 0.15)
				)
			)
		)
		(sheetname "/Supply/")
		(sheetfile "supply.kicad_sch")
		(attr smd)
		(fp_line
			(start -1.635 1.634)
			(end 1.634 1.634)
			(stroke
				(width 0.15)
				(type solid)
			)
			(layer "F.SilkS")
		)
		(fp_line
			(start -1.635 1.3)
			(end -1.635 1.634)
			(stroke
				(width 0.15)
				(type solid)
			)
			(layer "F.SilkS")
		)
		(fp_line
			(start 1.634 1.3)
			(end 1.634 1.634)
			(stroke
				(width 0.15)
				(type solid)
			)
			(layer "F.SilkS")
		)
		(fp_line
			(start -1.651 -1.651)
			(end -1.651 -1.317)
			(stroke
				(width 0.15)
				(type solid)
			)
			(layer "F.SilkS")
		)
		(fp_line
			(start -1.651 -1.651)
			(end 1.648 -1.651)
			(stroke
				(width 0.15)
				(type solid)
			)
			(layer "F.SilkS")
		)
		(fp_line
			(start 1.648 -1.651)
			(end 1.648 -1.317)
			(stroke
				(width 0.15)
				(type solid)
			)
			(layer "F.SilkS")
		)
		(fp_circle
			(center -1.9 -1.4)
			(end -1.85 -1.4)
			(stroke
				(width 0.15)
				(type solid)
			)
			(fill yes)
			(layer "F.SilkS")
		)
		(fp_rect
			(start -2 -1.8)
			(end 2 1.798)
			(stroke
				(width 0.05)
				(type solid)
			)
			(fill no)
			(layer "F.CrtYd")
		)
		(fp_line
			(start -1.6425 -1.4175)
			(end -1.4175 -1.6425)
			(stroke
				(width 0.15)
				(type solid)
			)
			(layer "F.Fab")
		)
		(fp_rect
			(start -1.651 -1.651)
			(end 1.648 1.648)
			(stroke
				(width 0.15)
				(type solid)
			)
			(fill no)
			(layer "F.Fab")
		)
		(fp_text user "License: Apache-2.0"
			(at -8 7.1 270)
			(layer "F.Fab")
			(effects
				(font
					(size 0.7 0.7)
					(thickness 0.15)
				)
				(justify left bottom)
			)
		)
		(fp_text user "${REFERENCE}"
			(at -8 4.7 270)
			(layer "F.Fab")
			(effects
				(font
					(size 0.7 0.7)
					(thickness 0.15)
				)
				(justify left bottom)
			)
		)
		(fp_text user "Author: Antmicro"
			(at -8 5.9 270)
			(layer "F.Fab")
			(effects
				(font
					(size 0.7 0.7)
					(thickness 0.15)
				)
				(justify left bottom)
			)
		)
		(pad "1" smd rect
			(at -1.436 -0.99 270)
			(size 0.99 0.405)
			(layers "F.Cu" "F.Mask" "F.Paste")
			(net 35 "VDC")
			(pinfunction "S")
			(pintype "passive")
		)
		(pad "2" smd rect
			(at -1.436 -0.332 270)
			(size 0.99 0.405)
			(layers "F.Cu" "F.Mask" "F.Paste")
			(net 35 "VDC")
			(pinfunction "S")
			(pintype "passive")
		)
		(pad "3" smd rect
			(at -1.436 0.33 270)
			(size 0.99 0.405)
			(layers "F.Cu" "F.Mask" "F.Paste")
			(net 35 "VDC")
			(pinfunction "S")
			(pintype "passive")
		)
		(pad "4" smd rect
			(at -1.436 0.988 270)
			(size 0.99 0.405)
			(layers "F.Cu" "F.Mask" "F.Paste")
			(net 813 "Net-(Q28-D)")
			(pinfunction "G")
			(pintype "passive")
		)
		(pad "5" smd custom
			(at 0.557 0 270)
			(size 1.725 2.235)
			(layers "F.Cu" "F.Mask" "F.Paste")
			(net 814 "Net-(Q29-D)")
			(pinfunction "D")
			(pintype "passive")
			(zone_connect 2)
			(options
				(clearance outline)
				(anchor rect)
			)
			(primitives
				(gr_poly
					(pts
						(xy 0.8625 0.1275) (xy 0.8625 -0.1275) (xy 1.3725 -0.1275) (xy 1.3725 -0.5325) (xy 0.8625 -0.5325)
						(xy 0.8625 -0.7875) (xy 1.3725 -0.7875) (xy 1.3725 -1.195) (xy 0.6125 -1.195) (xy 0.6125 1.195)
						(xy 1.3725 1.195) (xy 1.3725 0.7875) (xy 0.8625 0.7875) (xy 0.8625 0.5325) (xy 1.3725 0.5325)
						(xy 1.3725 0.1275)
					)
					(width 0)
					(fill yes)
				)
			)
		)
	)
	(footprint "antmicro-footprints:R_0402_1005Metric"
		(layer "F.Cu")
		(at 139.424499 183.279 90)
		(descr "Resistor SMD 0402")
		(tags "resistor SMD 0402")
		(property "Reference" "R66"
			(at -1.046 3.000501 90)
			(layer "F.SilkS")
			(effects
				(font
					(size 0.7 0.7)
					(thickness 0.15)
				)
				(justify left bottom)
			)
		)
		(property "Value" "R_330R_0402"
			(at -1.011843 1.772047 90)
			(layer "F.Fab")
			(effects
				(font
					(size 0.7 0.7)
					(thickness 0.15)
				)
				(justify left bottom)
			)
		)
		(property "Datasheet" "https://www.bourns.com/docs/product-datasheets/cr.pdf"
			(at 0 0 90)
			(layer "F.Fab")
			(hide yes)
			(effects
				(font
					(size 1.27 1.27)
					(thickness 0.15)
				)
			)
		)
		(property "Manufacturer" "Bourns"
			(at 0 0 90)
			(unlocked yes)
			(layer "F.Fab")
			(hide yes)
			(effects
				(font
					(size 1 1)
					(thickness 0.15)
				)
			)
		)
		(property "MPN" "CR0402-FX-3300GLF"
			(at 0 0 90)
			(unlocked yes)
			(layer "F.Fab")
			(hide yes)
			(effects
				(font
					(size 1 1)
					(thickness 0.15)
				)
			)
		)
		(property "Val" "330R"
			(at 0 0 90)
			(unlocked yes)
			(layer "F.Fab")
			(hide yes)
			(effects
				(font
					(size 1 1)
					(thickness 0.15)
				)
			)
		)
		(property "License" "Apache-2.0"
			(at 0 0 90)
			(unlocked yes)
			(layer "F.Fab")
			(hide yes)
			(effects
				(font
					(size 1 1)
					(thickness 0.15)
				)
			)
		)
		(property "Author" "Antmicro"
			(at 0 0 90)
			(unlocked yes)
			(layer "F.Fab")
			(hide yes)
			(effects
				(font
					(size 1 1)
					(thickness 0.15)
				)
			)
		)
		(property "Tolerance" "1%"
			(at 0 0 90)
			(unlocked yes)
			(layer "F.Fab")
			(hide yes)
			(effects
				(font
					(size 1 1)
					(thickness 0.15)
				)
			)
		)
		(sheetname "/Debug FTDI + VNA/")
		(sheetfile "debug-ftdi.kicad_sch")
		(attr smd)
		(fp_rect
			(start -0.925 -0.47)
			(end 0.925 0.47)
			(stroke
				(width 0.05)
				(type default)
			)
			(fill no)
			(layer "F.CrtYd")
		)
		(fp_rect
			(start -0.5 -0.25)
			(end 0.5 0.25)
			(stroke
				(width 0.15)
				(type solid)
			)
			(fill no)
			(layer "F.Fab")
		)
		(fp_text user "License: Apache-2.0"
			(at -0.95 5.169 90)
			(layer "F.Fab")
			(effects
				(font
					(size 0.7 0.7)
					(thickness 0.15)
				)
				(justify left bottom)
			)
		)
		(fp_text user "Author: Antmicro"
			(at -0.95 4.169 90)
			(layer "F.Fab")
			(effects
				(font
					(size 0.7 0.7)
					(thickness 0.15)
				)
				(justify left bottom)
			)
		)
		(fp_text user "${REFERENCE}"
			(at -0.95 3.168 90)
			(layer "F.Fab")
			(effects
				(font
					(size 0.7 0.7)
					(thickness 0.15)
				)
				(justify left bottom)
			)
		)
		(pad "1" smd roundrect
			(at -0.48 0 90)
			(size 0.59 0.64)
			(layers "F.Cu" "F.Mask" "F.Paste")
			(roundrect_rratio 0.25)
			(net 42 "Net-(D12-A)")
			(pintype "passive")
		)
		(pad "2" smd roundrect
			(at 0.48 0 90)
			(size 0.59 0.64)
			(layers "F.Cu" "F.Mask" "F.Paste")
			(roundrect_rratio 0.25)
			(net 445 "/Debug FTDI + VNA/LED_TX1")
			(pintype "passive")
		)
	)
	(footprint "antmicro-footprints:C_0402_1005Metric"
		(layer "F.Cu")
		(at 127.306 176.022 90)
		(descr "Capacitor SMD 0402")
		(tags "capacitor SMD 0402")
		(property "Reference" "C273"
			(at 1.2 0.49 90)
			(layer "F.SilkS")
			(effects
				(font
					(size 0.7 0.7)
					(thickness 0.15)
				)
				(justify left bottom)
			)
		)
		(property "Value" "C_100n_0402"
			(at -1.022927 2.155213 90)
			(layer "F.Fab")
			(effects
				(font
					(size 0.7 0.7)
					(thickness 0.15)
				)
				(justify left bottom)
			)
		)
		(property "Datasheet" "https://www.murata.com/products/productdetail?partno=GRM155R61H104KE14%23"
			(at 0 0 90)
			(layer "F.Fab")
			(hide yes)
			(effects
				(font
					(size 1.27 1.27)
					(thickness 0.15)
				)
			)
		)
		(property "MPN" "GRM155R61H104KE14D"
			(at 0 0 90)
			(unlocked yes)
			(layer "F.Fab")
			(hide yes)
			(effects
				(font
					(size 1 1)
					(thickness 0.15)
				)
			)
		)
		(property "Manufacturer" "Murata"
			(at 0 0 90)
			(unlocked yes)
			(layer "F.Fab")
			(hide yes)
			(effects
				(font
					(size 1 1)
					(thickness 0.15)
				)
			)
		)
		(property "License" "Apache-2.0"
			(at 0 0 90)
			(unlocked yes)
			(layer "F.Fab")
			(hide yes)
			(effects
				(font
					(size 1 1)
					(thickness 0.15)
				)
			)
		)
		(property "Author" "Antmicro"
			(at 0 0 90)
			(unlocked yes)
			(layer "F.Fab")
			(hide yes)
			(effects
				(font
					(size 1 1)
					(thickness 0.15)
				)
			)
		)
		(property "Val" "100n"
			(at 0 0 90)
			(unlocked yes)
			(layer "F.Fab")
			(hide yes)
			(effects
				(font
					(size 1 1)
					(thickness 0.15)
				)
			)
		)
		(property "Voltage" "50V"
			(at 0 0 90)
			(unlocked yes)
			(layer "F.Fab")
			(hide yes)
			(effects
				(font
					(size 1 1)
					(thickness 0.15)
				)
			)
		)
		(property "Dielectric" "X5R"
			(at 0 0 90)
			(unlocked yes)
			(layer "F.Fab")
			(hide yes)
			(effects
				(font
					(size 1 1)
					(thickness 0.15)
				)
			)
		)
		(property "Public" ""
			(at 0 0 90)
			(unlocked yes)
			(layer "F.Fab")
			(hide yes)
			(effects
				(font
					(size 1 1)
					(thickness 0.15)
				)
			)
		)
		(sheetname "/HDMI + SD Card/")
		(sheetfile "hdmi-sd-card.kicad_sch")
		(attr smd)
		(fp_rect
			(start -0.925 -0.47)
			(end 0.925 0.47)
			(stroke
				(width 0.05)
				(type default)
			)
			(fill no)
			(layer "F.CrtYd")
		)
		(fp_line
			(start 0.504 -0.25)
			(end 0.504 0.248)
			(stroke
				(width 0.15)
				(type solid)
			)
			(layer "F.Fab")
		)
		(fp_line
			(start -0.494 -0.25)
			(end 0.504 -0.25)
			(stroke
				(width 0.15)
				(type solid)
			)
			(layer "F.Fab")
		)
		(fp_line
			(start 0.504 0.248)
			(end -0.494 0.248)
			(stroke
				(width 0.15)
				(type solid)
			)
			(layer "F.Fab")
		)
		(fp_line
			(start -0.494 0.248)
			(end -0.494 -0.25)
			(stroke
				(width 0.15)
				(type solid)
			)
			(layer "F.Fab")
		)
		(fp_text user "${REFERENCE}"
			(at -0.939 4.599 90)
			(layer "F.Fab")
			(effects
				(font
					(size 0.7 0.7)
					(thickness 0.15)
				)
				(justify left bottom)
			)
		)
		(fp_text user "Author: Antmicro"
			(at -0.939 3.399 90)
			(layer "F.Fab")
			(effects
				(font
					(size 0.7 0.7)
					(thickness 0.15)
				)
				(justify left bottom)
			)
		)
		(fp_text user "License: Apache-2.0"
			(at -0.939 5.799 90)
			(layer "F.Fab")
			(effects
				(font
					(size 0.7 0.7)
					(thickness 0.15)
				)
				(justify left bottom)
			)
		)
		(pad "1" smd roundrect
			(at -0.48 0 90)
			(size 0.59 0.64)
			(layers "F.Cu" "F.Mask" "F.Paste")
			(roundrect_rratio 0.25)
			(net 151 "+3V3")
			(pintype "passive")
		)
		(pad "2" smd roundrect
			(at 0.48 0 90)
			(size 0.59 0.64)
			(layers "F.Cu" "F.Mask" "F.Paste")
			(roundrect_rratio 0.25)
			(net 1 "GND")
			(pintype "passive")
		)
	)
	(footprint "antmicro-footprints:R_0402_1005Metric"
		(layer "F.Cu")
		(at 252.4 183.549 180)
		(descr "Resistor SMD 0402")
		(tags "resistor SMD 0402")
		(property "Reference" "R222"
			(at 1 -0.375 0)
			(layer "F.SilkS")
			(effects
				(font
					(size 0.7 0.7)
					(thickness 0.15)
				)
				(justify right bottom)
			)
		)
		(property "Value" "R_0R_0402"
			(at -1.011843 1.772047 0)
			(layer "F.Fab")
			(effects
				(font
					(size 0.7 0.7)
					(thickness 0.15)
				)
				(justify right bottom)
			)
		)
		(property "Datasheet" "https://industrial.panasonic.com/cdbs/www-data/pdf/RDA0000/AOA0000C301.pdf"
			(at 0 0 180)
			(layer "F.Fab")
			(hide yes)
			(effects
				(font
					(size 1.27 1.27)
					(thickness 0.15)
				)
			)
		)
		(property "MPN" "ERJ2GE0R00X"
			(at 0 0 180)
			(unlocked yes)
			(layer "F.Fab")
			(hide yes)
			(effects
				(font
					(size 1 1)
					(thickness 0.15)
				)
			)
		)
		(property "Manufacturer" "Panasonic"
			(at 0 0 180)
			(unlocked yes)
			(layer "F.Fab")
			(hide yes)
			(effects
				(font
					(size 1 1)
					(thickness 0.15)
				)
			)
		)
		(property "License" "Apache-2.0"
			(at 0 0 180)
			(unlocked yes)
			(layer "F.Fab")
			(hide yes)
			(effects
				(font
					(size 1 1)
					(thickness 0.15)
				)
			)
		)
		(property "Author" "Antmicro"
			(at 0 0 180)
			(unlocked yes)
			(layer "F.Fab")
			(hide yes)
			(effects
				(font
					(size 1 1)
					(thickness 0.15)
				)
			)
		)
		(property "Val" "0R"
			(at 0 0 180)
			(unlocked yes)
			(layer "F.Fab")
			(hide yes)
			(effects
				(font
					(size 1 1)
					(thickness 0.15)
				)
			)
		)
		(property "Tolerance" "~"
			(at 0 0 180)
			(unlocked yes)
			(layer "F.Fab")
			(hide yes)
			(effects
				(font
					(size 1 1)
					(thickness 0.15)
				)
			)
		)
		(property "Current" "1A"
			(at 0 0 180)
			(unlocked yes)
			(layer "F.Fab")
			(hide yes)
			(effects
				(font
					(size 1 1)
					(thickness 0.15)
				)
			)
		)
		(sheetname "/I^{2}C + I3C/")
		(sheetfile "i2c.kicad_sch")
		(attr smd)
		(fp_rect
			(start -0.925 -0.47)
			(end 0.925 0.47)
			(stroke
				(width 0.05)
				(type default)
			)
			(fill no)
			(layer "F.CrtYd")
		)
		(fp_rect
			(start -0.5 -0.25)
			(end 0.5 0.25)
			(stroke
				(width 0.15)
				(type solid)
			)
			(fill no)
			(layer "F.Fab")
		)
		(fp_text user "${REFERENCE}"
			(at -0.95 3.168 180)
			(layer "F.Fab")
			(effects
				(font
					(size 0.7 0.7)
					(thickness 0.15)
				)
				(justify left bottom)
			)
		)
		(fp_text user "License: Apache-2.0"
			(at -0.95 5.169 180)
			(layer "F.Fab")
			(effects
				(font
					(size 0.7 0.7)
					(thickness 0.15)
				)
				(justify left bottom)
			)
		)
		(fp_text user "Author: Antmicro"
			(at -0.95 4.169 180)
			(layer "F.Fab")
			(effects
				(font
					(size 0.7 0.7)
					(thickness 0.15)
				)
				(justify left bottom)
			)
		)
		(pad "1" smd roundrect
			(at -0.48 0 180)
			(size 0.59 0.64)
			(layers "F.Cu" "F.Mask" "F.Paste")
			(roundrect_rratio 0.25)
			(net 664 "Net-(C325-Pad2)")
			(pintype "passive")
		)
		(pad "2" smd roundrect
			(at 0.48 0 180)
			(size 0.59 0.64)
			(layers "F.Cu" "F.Mask" "F.Paste")
			(roundrect_rratio 0.25)
			(net 151 "+3V3")
			(pintype "passive")
		)
	)
)
